# BASEBOARD_FAB2 (Tioga Pass) — schematic netlist excerpt (pin names and nets, part order shuffled) for the footprints in the layout excerpt that follows; sources: Cadence DE-HDL packaged netlist, KiCad conversion of Wiwynn_Tioga_Pass_MB.brd

R9E24  RES  221 1.0% CHIP  pkg 0402  page 151 : A = FM_HEARTBEAT_LED_A ; B = P3V3_STBY
R9F11  RES  22.1 1.0% CHIP  pkg 0402  page 238 : A = PWRGD_P1V15_BMC_STBY_R ; B = PWRGD_P1V15_BMC_STBY
C7B10  CAP  100.0PF 50V 5% COG  pkg 0402LF  page 232 : A = VR_FB_PVPP_DEF ; B = VR_COMP_PVPP_DEF_3

(kicad_pcb
	(version 20260206)
	(generator "pcbnew")
	(generator_version "10.0")
	(general
		(thickness 1.6)
		(legacy_teardrops no)
	)
	(paper "A4")
	(title_block
		(title "Wiwynn_Tioga_Pass_MB.brd")
		(comment 1 "Tioga Pass / footprints 486-488 of 4770")
	)
	(layers
		(0 "F.Cu" signal "TOP")
		(4 "In1.Cu" signal "L2GND")
		(6 "In2.Cu" signal "L3")
		(8 "In3.Cu" signal "L4GND")
		(10 "In4.Cu" signal "L5")
		(12 "In5.Cu" signal "L6GND")
		(14 "In6.Cu" signal "L7VCC")
		(16 "In7.Cu" signal "L8VCC")
		(18 "In8.Cu" signal "L9GND")
		(20 "In9.Cu" signal "L10")
		(22 "In10.Cu" signal "L11GND")
		(24 "In11.Cu" signal "L12")
		(26 "In12.Cu" signal "L13GND")
		(2 "B.Cu" signal "BOTTOM")
		(9 "F.Adhes" user "F.Adhesive")
		(11 "B.Adhes" user "B.Adhesive")
		(13 "F.Paste" user "Package Geometry/Pastemask Top")
		(15 "B.Paste" user "Package Geometry/Pastemask Bottom")
		(5 "F.SilkS" user "Ref Des/Silkscreen Top")
		(7 "B.SilkS" user "Ref Des/Silkscreen Bottom")
		(1 "F.Mask" user "Board Geometry/Soldermask Top")
		(3 "B.Mask" user "Board Geometry/Soldermask Bottom")
		(17 "Dwgs.User" user "User.Drawings")
		(19 "Cmts.User" user "User.Comments")
		(21 "Eco1.User" user "User.Eco1")
		(23 "Eco2.User" user "User.Eco2")
		(25 "Edge.Cuts" user "Board Geometry/Outline")
		(27 "Margin" user)
		(31 "F.CrtYd" user "Package Geometry/Place Bound Top")
		(29 "B.CrtYd" user "Package Geometry/Place Bound Bottom")
		(35 "F.Fab" user "Ref Des/Assembly Top")
		(33 "B.Fab" user "Ref Des/Assembly Bottom")
	)
	(footprint ""
		(layer "F.Cu")
		(at 342.4428 -127.5588 90)
		(property "Reference" "C7B10"
			(at 0 0 90)
			(layer "F.SilkS")
			(hide yes)
			(effects
				(font
					(size 1.27 1.27)
				)
			)
		)
		(property "Value" ""
			(at 0 0 90)
			(layer "F.Fab")
			(effects
				(font
					(size 1.27 1.27)
				)
			)
		)
		(duplicate_pad_numbers_are_jumpers no)
		(fp_poly
			(pts
				(xy 0.3048 -0.1016) (xy 0.3048 0.9906) (xy -0.3048 0.9906) (xy -0.3048 -0.1016)
			)
			(stroke
				(width 0)
				(type default)
			)
			(fill no)
			(layer "F.CrtYd")
		)
		(fp_line
			(start 0.3048 -0.1016)
			(end -0.3048 -0.1016)
			(stroke
				(width 0.1)
				(type default)
			)
			(layer "F.Fab")
		)
		(fp_line
			(start -0.3048 -0.1016)
			(end -0.3048 0.9906)
			(stroke
				(width 0.1)
				(type default)
			)
			(layer "F.Fab")
		)
		(fp_line
			(start 0.3048 0.9906)
			(end 0.3048 -0.1016)
			(stroke
				(width 0.1)
				(type default)
			)
			(layer "F.Fab")
		)
		(fp_line
			(start -0.3048 0.9906)
			(end 0.3048 0.9906)
			(stroke
				(width 0.1)
				(type default)
			)
			(layer "F.Fab")
		)
		(pad "1" smd rect
			(at 0 0 90)
			(size 0.508 0.508)
			(layers "F.Cu" "F.Mask" "F.Paste")
			(net "VR_FB_PVPP_DEF")
		)
		(pad "2" smd rect
			(at 0 0.889 90)
			(size 0.508 0.508)
			(layers "F.Cu" "F.Mask" "F.Paste")
			(net "VR_COMP_PVPP_DEF_3")
		)
		(zone
			(layer "F.Cu")
			(hatch none 0.5)
			(connect_pads
				(clearance 0)
			)
			(min_thickness 0.25)
			(keepout
				(tracks allowed)
				(vias not_allowed)
				(pads allowed)
				(copperpour not_allowed)
				(footprints allowed)
			)
			(placement
				(enabled no)
				(sheetname "")
			)
			(fill
				(thermal_gap 0.5)
				(thermal_bridge_width 0.5)
				(island_removal_mode 0)
			)
			(polygon
				(pts
					(xy 342.6968 -127.3048) (xy 342.6968 -127.8128) (xy 343.0778 -127.8128) (xy 343.0778 -127.3048)
				)
			)
		)
		(zone
			(layer "F.Cu")
			(hatch none 0.5)
			(connect_pads
				(clearance 0)
			)
			(min_thickness 0.25)
			(keepout
				(tracks not_allowed)
				(vias allowed)
				(pads allowed)
				(copperpour not_allowed)
				(footprints allowed)
			)
			(placement
				(enabled no)
				(sheetname "")
			)
			(fill
				(thermal_gap 0.5)
				(thermal_bridge_width 0.5)
				(island_removal_mode 0)
			)
			(polygon
				(pts
					(xy 343.0778 -127.3048) (xy 343.0778 -127.8128) (xy 342.6968 -127.8128) (xy 342.6968 -127.3048)
				)
			)
		)
	)
	(footprint ""
		(layer "F.Cu")
		(at 462.114392 -37.956998)
		(property "Reference" "R9F11"
			(at 0 0 0)
			(layer "F.SilkS")
			(hide yes)
			(effects
				(font
					(size 1.27 1.27)
				)
			)
		)
		(property "Value" ""
			(at 0 0 0)
			(layer "F.Fab")
			(effects
				(font
					(size 1.27 1.27)
				)
			)
		)
		(duplicate_pad_numbers_are_jumpers no)
		(fp_poly
			(pts
				(xy -0.2794 -0.1016) (xy 0.2794 -0.1016) (xy 0.2794 0.9906) (xy -0.2794 0.9906)
			)
			(stroke
				(width 0)
				(type default)
			)
			(fill no)
			(layer "F.CrtYd")
		)
		(fp_line
			(start -0.2794 -0.1016)
			(end -0.2794 0.9906)
			(stroke
				(width 0.1)
				(type default)
			)
			(layer "F.Fab")
		)
		(fp_line
			(start -0.2794 0.9906)
			(end 0.2794 0.9906)
			(stroke
				(width 0.1)
				(type default)
			)
			(layer "F.Fab")
		)
		(fp_line
			(start 0.2794 -0.1016)
			(end -0.2794 -0.1016)
			(stroke
				(width 0.1)
				(type default)
			)
			(layer "F.Fab")
		)
		(fp_line
			(start 0.2794 0.9906)
			(end 0.2794 -0.1016)
			(stroke
				(width 0.1)
				(type default)
			)
			(layer "F.Fab")
		)
		(pad "1" smd rect
			(at 0 0)
			(size 0.508 0.508)
			(layers "F.Cu" "F.Mask" "F.Paste")
			(net "PWRGD_P1V15_BMC_STBY_R")
		)
		(pad "2" smd rect
			(at 0 0.889)
			(size 0.508 0.508)
			(layers "F.Cu" "F.Mask" "F.Paste")
			(net "PWRGD_P1V15_BMC_STBY")
		)
		(zone
			(layer "F.Cu")
			(hatch none 0.5)
			(connect_pads
				(clearance 0)
			)
			(min_thickness 0.25)
			(keepout
				(tracks allowed)
				(vias not_allowed)
				(pads allowed)
				(copperpour not_allowed)
				(footprints allowed)
			)
			(placement
				(enabled no)
				(sheetname "")
			)
			(fill
				(thermal_gap 0.5)
				(thermal_bridge_width 0.5)
				(island_removal_mode 0)
			)
			(polygon
				(pts
					(xy 461.860392 -37.702998) (xy 462.368392 -37.702998) (xy 462.368392 -37.321998) (xy 461.860392 -37.321998)
				)
			)
		)
		(zone
			(layer "F.Cu")
			(hatch none 0.5)
			(connect_pads
				(clearance 0)
			)
			(min_thickness 0.25)
			(keepout
				(tracks not_allowed)
				(vias allowed)
				(pads allowed)
				(copperpour not_allowed)
				(footprints allowed)
			)
			(placement
				(enabled no)
				(sheetname "")
			)
			(fill
				(thermal_gap 0.5)
				(thermal_bridge_width 0.5)
				(island_removal_mode 0)
			)
			(polygon
				(pts
					(xy 461.860392 -37.321998) (xy 462.368392 -37.321998) (xy 462.368392 -37.702998) (xy 461.860392 -37.702998)
				)
			)
		)
	)
	(footprint ""
		(layer "F.Cu")
		(at 454.025 -37.846 180)
		(property "Reference" "R9E24"
			(at 0 0 180)
			(layer "F.SilkS")
			(hide yes)
			(effects
				(font
					(size 1.27 1.27)
				)
			)
		)
		(property "Value" ""
			(at 0 0 180)
			(layer "F.Fab")
			(effects
				(font
					(size 1.27 1.27)
				)
			)
		)
		(duplicate_pad_numbers_are_jumpers no)
		(fp_poly
			(pts
				(xy -0.2794 -0.1016) (xy 0.2794 -0.1016) (xy 0.2794 0.9906) (xy -0.2794 0.9906)
			)
			(stroke
				(width 0)
				(type default)
			)
			(fill no)
			(layer "F.CrtYd")
		)
		(fp_line
			(start 0.2794 0.9906)
			(end 0.2794 -0.1016)
			(stroke
				(width 0.1)
				(type default)
			)
			(layer "F.Fab")
		)
		(fp_line
			(start 0.2794 -0.1016)
			(end -0.2794 -0.1016)
			(stroke
				(width 0.1)
				(type default)
			)
			(layer "F.Fab")
		)
		(fp_line
			(start -0.2794 0.9906)
			(end 0.2794 0.9906)
			(stroke
				(width 0.1)
				(type default)
			)
			(layer "F.Fab")
		)
		(fp_line
			(start -0.2794 -0.1016)
			(end -0.2794 0.9906)
			(stroke
				(width 0.1)
				(type default)
			)
			(layer "F.Fab")
		)
		(pad "1" smd rect
			(at 0 0 180)
			(size 0.508 0.508)
			(layers "F.Cu" "F.Mask" "F.Paste")
			(net "FM_HEARTBEAT_LED_A")
		)
		(pad "2" smd rect
			(at 0 0.889 180)
			(size 0.508 0.508)
			(layers "F.Cu" "F.Mask" "F.Paste")
			(net "P3V3_STBY")
		)
		(zone
			(layer "F.Cu")
			(hatch none 0.5)
			(connect_pads
				(clearance 0)
			)
			(min_thickness 0.25)
			(keepout
				(tracks not_allowed)
				(vias allowed)
				(pads allowed)
				(copperpour not_allowed)
				(footprints allowed)
			)
			(placement
				(enabled no)
				(sheetname "")
			)
			(fill
				(thermal_gap 0.5)
				(thermal_bridge_width 0.5)
				(island_removal_mode 0)
			)
			(polygon
				(pts
					(xy 454.279 -38.481) (xy 453.771 -38.481) (xy 453.771 -38.1) (xy 454.279 -38.1)
				)
			)
		)
		(zone
			(layer "F.Cu")
			(hatch none 0.5)
			(connect_pads
				(clearance 0)
			)
			(min_thickness 0.25)
			(keepout
				(tracks allowed)
				(vias not_allowed)
				(pads allowed)
				(copperpour not_allowed)
				(footprints allowed)
			)
			(placement
				(enabled no)
				(sheetname "")
			)
			(fill
				(thermal_gap 0.5)
				(thermal_bridge_width 0.5)
				(island_removal_mode 0)
			)
			(polygon
				(pts
					(xy 454.279 -38.1) (xy 453.771 -38.1) (xy 453.771 -38.481) (xy 454.279 -38.481)
				)
			)
		)
	)
)
